(kicad_pcb
	(version 20260206)
	(generator "pcbnew")
	(generator_version "10.0")
	(general
		(thickness 1.6)
		(legacy_teardrops no)
	)
	(paper "A4")
	(title_block
		(title "12092022_DA0F0TFB6D0_F0T_FAN_BOARD_MP5048_D_brd_v02_OCP.brd")
		(comment 1 "Grand Teton / footprints 664-670 of 924")
	)
	(layers
		(0 "F.Cu" signal "TOP")
		(4 "In1.Cu" signal "GND")
		(6 "In2.Cu" signal "IN1")
		(8 "In3.Cu" signal "IN2")
		(10 "In4.Cu" signal "GND1")
		(2 "B.Cu" signal "BOTTOM")
		(9 "F.Adhes" user "F.Adhesive")
		(11 "B.Adhes" user "B.Adhesive")
		(13 "F.Paste" user "Package Geometry/Pastemask Top")
		(15 "B.Paste" user "Package Geometry/Pastemask Bottom")
		(5 "F.SilkS" user "Ref Des/Silkscreen Top")
		(7 "B.SilkS" user "Ref Des/Silkscreen Bottom")
		(1 "F.Mask" user "Board Geometry/Soldermask Top")
		(3 "B.Mask" user "Board Geometry/Soldermask Bottom")
		(17 "Dwgs.User" user "User.Drawings")
		(19 "Cmts.User" user "User.Comments")
		(21 "Eco1.User" user "User.Eco1")
		(23 "Eco2.User" user "User.Eco2")
		(25 "Edge.Cuts" user "Board Geometry/Outline")
		(27 "Margin" user)
		(31 "F.CrtYd" user "Package Geometry/Place Bound Top")
		(29 "B.CrtYd" user "Package Geometry/Place Bound Bottom")
		(35 "F.Fab" user "Ref Des/Assembly Top")
		(33 "B.Fab" user "Ref Des/Assembly Bottom")
	)
	(footprint ""
		(layer "F.Cu")
		(at 25.527 -179.451 180)
		(property "Reference" "C2081"
			(at 0 0 180)
			(layer "F.SilkS")
			(hide yes)
			(effects
				(font
					(size 1.27 1.27)
				)
			)
		)
		(property "Value" ""
			(at 0 0 180)
			(layer "F.Fab")
			(effects
				(font
					(size 1.27 1.27)
				)
			)
		)
		(duplicate_pad_numbers_are_jumpers no)
		(fp_line
			(start 0.7874 0.4064)
			(end -0.7874 0.4064)
			(stroke
				(width 0.1524)
				(type default)
			)
			(layer "F.SilkS")
		)
		(fp_line
			(start 0.7874 -0.4064)
			(end 0.7874 0.4064)
			(stroke
				(width 0.1524)
				(type default)
			)
			(layer "F.SilkS")
		)
		(fp_line
			(start -0.7874 0.4064)
			(end -0.7874 -0.4064)
			(stroke
				(width 0.1524)
				(type default)
			)
			(layer "F.SilkS")
		)
		(fp_line
			(start -0.7874 -0.4064)
			(end 0.7874 -0.4064)
			(stroke
				(width 0.1524)
				(type default)
			)
			(layer "F.SilkS")
		)
		(fp_line
			(start 0.67945 0.3048)
			(end 0.120396 0.3048)
			(stroke
				(width 0.1)
				(type default)
			)
			(layer "F.Fab")
		)
		(fp_line
			(start 0.67945 -0.3048)
			(end 0.67945 0.3048)
			(stroke
				(width 0.1)
				(type default)
			)
			(layer "F.Fab")
		)
		(fp_line
			(start 0.12065 -0.2794)
			(end 0.12065 -0.3048)
			(stroke
				(width 0.1)
				(type default)
			)
			(layer "F.Fab")
		)
		(fp_line
			(start 0.12065 -0.3048)
			(end 0.67945 -0.3048)
			(stroke
				(width 0.1)
				(type default)
			)
			(layer "F.Fab")
		)
		(fp_line
			(start 0.120396 0.3048)
			(end 0.120396 0.2794)
			(stroke
				(width 0.1)
				(type default)
			)
			(layer "F.Fab")
		)
		(fp_line
			(start 0.120396 0.2794)
			(end -0.12065 0.2794)
			(stroke
				(width 0.1)
				(type default)
			)
			(layer "F.Fab")
		)
		(fp_line
			(start -0.12065 0.3048)
			(end -0.67945 0.3048)
			(stroke
				(width 0.1)
				(type default)
			)
			(layer "F.Fab")
		)
		(fp_line
			(start -0.12065 0.2794)
			(end -0.12065 0.3048)
			(stroke
				(width 0.1)
				(type default)
			)
			(layer "F.Fab")
		)
		(fp_line
			(start -0.12065 -0.2794)
			(end 0.12065 -0.2794)
			(stroke
				(width 0.1)
				(type default)
			)
			(layer "F.Fab")
		)
		(fp_line
			(start -0.12065 -0.305054)
			(end -0.12065 -0.2794)
			(stroke
				(width 0.1)
				(type default)
			)
			(layer "F.Fab")
		)
		(fp_line
			(start -0.67945 0.3048)
			(end -0.67945 -0.305054)
			(stroke
				(width 0.1)
				(type default)
			)
			(layer "F.Fab")
		)
		(fp_line
			(start -0.67945 -0.305054)
			(end -0.12065 -0.305054)
			(stroke
				(width 0.1)
				(type default)
			)
			(layer "F.Fab")
		)
		(pad "1" smd circle
			(at -0.40005 0 180)
			(size 0 0)
			(layers "F.Cu" "F.Mask" "F.Paste")
			(net "P52V_FAN_2_BUFF_EN_R")
		)
		(pad "2" smd circle
			(at 0.40005 0 180)
			(size 0 0)
			(layers "F.Cu" "F.Mask" "F.Paste")
			(net "GND")
		)
	)
	(footprint ""
		(layer "F.Cu")
		(at 37.338 -289.941)
		(property "Reference" "D264"
			(at 1.905 0.02667 0)
			(unlocked yes)
			(layer "F.SilkS")
			(effects
				(font
					(size 0.7874 0.5842)
					(thickness 0.1524)
				)
				(justify left)
			)
		)
		(property "Value" ""
			(at 0 0 0)
			(layer "F.Fab")
			(effects
				(font
					(size 1.27 1.27)
				)
			)
		)
		(duplicate_pad_numbers_are_jumpers no)
		(fp_line
			(start -0.854964 -0.450088)
			(end -0.854964 0.450088)
			(stroke
				(width 0.1524)
				(type default)
			)
			(layer "F.SilkS")
		)
		(fp_line
			(start -0.854964 0.450088)
			(end 0.925068 0.450088)
			(stroke
				(width 0.1524)
				(type default)
			)
			(layer "F.SilkS")
		)
		(fp_line
			(start 0.845058 0.4064)
			(end 0.845058 -0.381)
			(stroke
				(width 0.1524)
				(type default)
			)
			(layer "F.SilkS")
		)
		(fp_line
			(start 0.870458 -0.2794)
			(end 0.845058 0.4064)
			(stroke
				(width 0.1524)
				(type default)
			)
			(layer "F.SilkS")
		)
		(fp_line
			(start 0.94488 -0.450088)
			(end -0.854964 -0.450088)
			(stroke
				(width 0.1524)
				(type default)
			)
			(layer "F.SilkS")
		)
		(fp_line
			(start 0.94488 0.450088)
			(end 0.94488 -0.450088)
			(stroke
				(width 0.1524)
				(type default)
			)
			(layer "F.SilkS")
		)
		(fp_line
			(start -0.54991 -0.350012)
			(end -0.54991 0.350012)
			(stroke
				(width 0.1)
				(type default)
			)
			(layer "F.Fab")
		)
		(fp_line
			(start -0.54991 0.350012)
			(end 0.54991 0.350012)
			(stroke
				(width 0.1)
				(type default)
			)
			(layer "F.Fab")
		)
		(fp_line
			(start 0.54991 -0.350012)
			(end -0.54991 -0.350012)
			(stroke
				(width 0.1)
				(type default)
			)
			(layer "F.Fab")
		)
		(fp_line
			(start 0.54991 0.350012)
			(end 0.54991 -0.350012)
			(stroke
				(width 0.1)
				(type default)
			)
			(layer "F.Fab")
		)
		(fp_text user "+"
			(at -2.00025 1.143 90)
			(unlocked yes)
			(layer "F.SilkS")
			(effects
				(font
					(size 1.905 1.4224)
					(thickness 0.1524)
				)
				(justify left)
			)
		)
		(fp_text user "-"
			(at 2.159 0.22225 180)
			(unlocked yes)
			(layer "F.SilkS")
			(effects
				(font
					(size 1.905 1.4224)
					(thickness 0.1524)
				)
				(justify left)
			)
		)
		(fp_text user "+"
			(at -0.808228 0.239014 180)
			(unlocked yes)
			(layer "F.Fab")
			(effects
				(font
					(size 1.905 1.4224)
					(thickness 0.1524)
				)
				(justify left)
			)
		)
		(fp_text user "-"
			(at 2.48539 0.239014 180)
			(unlocked yes)
			(layer "F.Fab")
			(effects
				(font
					(size 1.905 1.4224)
					(thickness 0.1524)
				)
				(justify left)
			)
		)
		(pad "A" smd rect
			(at -0.424942 0)
			(size 0.5588 0.6096)
			(layers "F.Cu" "F.Mask" "F.Paste")
			(net "GND")
		)
		(pad "C" smd rect
			(at 0.424942 0 180)
			(size 0.5588 0.6096)
			(layers "F.Cu" "F.Mask" "F.Paste")
			(net "FAN_0_OK_R_LED_N")
		)
	)
	(footprint ""
		(layer "F.Cu")
		(at 47.879 -124.46 180)
		(property "Reference" "C2037"
			(at 0 0 180)
			(layer "F.SilkS")
			(hide yes)
			(effects
				(font
					(size 1.27 1.27)
				)
			)
		)
		(property "Value" ""
			(at 0 0 180)
			(layer "F.Fab")
			(effects
				(font
					(size 1.27 1.27)
				)
			)
		)
		(duplicate_pad_numbers_are_jumpers no)
		(fp_line
			(start 0.7874 0.4064)
			(end -0.7874 0.4064)
			(stroke
				(width 0.1524)
				(type default)
			)
			(layer "F.SilkS")
		)
		(fp_line
			(start 0.7874 -0.4064)
			(end 0.7874 0.4064)
			(stroke
				(width 0.1524)
				(type default)
			)
			(layer "F.SilkS")
		)
		(fp_line
			(start -0.7874 0.4064)
			(end -0.7874 -0.4064)
			(stroke
				(width 0.1524)
				(type default)
			)
			(layer "F.SilkS")
		)
		(fp_line
			(start -0.7874 -0.4064)
			(end 0.7874 -0.4064)
			(stroke
				(width 0.1524)
				(type default)
			)
			(layer "F.SilkS")
		)
		(fp_line
			(start 0.6858 0.3048)
			(end 0.1016 0.3048)
			(stroke
				(width 0.1)
				(type default)
			)
			(layer "F.Fab")
		)
		(fp_line
			(start 0.6858 -0.3048)
			(end 0.6858 0.3048)
			(stroke
				(width 0.1)
				(type default)
			)
			(layer "F.Fab")
		)
		(fp_line
			(start 0.1016 0.3048)
			(end 0.1016 0.2794)
			(stroke
				(width 0.1)
				(type default)
			)
			(layer "F.Fab")
		)
		(fp_line
			(start 0.1016 0.2794)
			(end -0.1016 0.2794)
			(stroke
				(width 0.1)
				(type default)
			)
			(layer "F.Fab")
		)
		(fp_line
			(start 0.1016 -0.2794)
			(end 0.1016 -0.3048)
			(stroke
				(width 0.1)
				(type default)
			)
			(layer "F.Fab")
		)
		(fp_line
			(start 0.1016 -0.3048)
			(end 0.6858 -0.3048)
			(stroke
				(width 0.1)
				(type default)
			)
			(layer "F.Fab")
		)
		(fp_line
			(start -0.1016 0.3048)
			(end -0.6858 0.3048)
			(stroke
				(width 0.1)
				(type default)
			)
			(layer "F.Fab")
		)
		(fp_line
			(start -0.1016 0.2794)
			(end -0.1016 0.3048)
			(stroke
				(width 0.1)
				(type default)
			)
			(layer "F.Fab")
		)
		(fp_line
			(start -0.1016 -0.2794)
			(end 0.1016 -0.2794)
			(stroke
				(width 0.1)
				(type default)
			)
			(layer "F.Fab")
		)
		(fp_line
			(start -0.1016 -0.3048)
			(end -0.1016 -0.2794)
			(stroke
				(width 0.1)
				(type default)
			)
			(layer "F.Fab")
		)
		(fp_line
			(start -0.6858 0.3048)
			(end -0.6858 -0.3048)
			(stroke
				(width 0.1)
				(type default)
			)
			(layer "F.Fab")
		)
		(fp_line
			(start -0.6858 -0.3048)
			(end -0.1016 -0.3048)
			(stroke
				(width 0.1)
				(type default)
			)
			(layer "F.Fab")
		)
		(pad "1" smd rect
			(at -0.40005 0)
			(size 0.4572 0.508)
			(layers "F.Cu" "F.Mask" "F.Paste")
			(net "GND")
		)
		(pad "2" smd rect
			(at 0.40005 0)
			(size 0.4572 0.508)
			(layers "F.Cu" "F.Mask" "F.Paste")
			(net "P12V_LED_FAN2")
		)
	)
	(footprint ""
		(layer "F.Cu")
		(at 14.732 -260.096 180)
		(property "Reference" "PR75"
			(at 0 0 180)
			(layer "F.SilkS")
			(hide yes)
			(effects
				(font
					(size 1.27 1.27)
				)
			)
		)
		(property "Value" ""
			(at 0 0 180)
			(layer "F.Fab")
			(effects
				(font
					(size 1.27 1.27)
				)
			)
		)
		(duplicate_pad_numbers_are_jumpers no)
		(fp_line
			(start 0.7874 0.4064)
			(end -0.7874 0.4064)
			(stroke
				(width 0.1524)
				(type default)
			)
			(layer "F.SilkS")
		)
		(fp_line
			(start 0.7874 -0.4064)
			(end 0.7874 0.4064)
			(stroke
				(width 0.1524)
				(type default)
			)
			(layer "F.SilkS")
		)
		(fp_line
			(start -0.7874 0.4064)
			(end -0.7874 -0.4064)
			(stroke
				(width 0.1524)
				(type default)
			)
			(layer "F.SilkS")
		)
		(fp_line
			(start -0.7874 -0.4064)
			(end 0.7874 -0.4064)
			(stroke
				(width 0.1524)
				(type default)
			)
			(layer "F.SilkS")
		)
		(fp_line
			(start 0.67945 0.3048)
			(end 0.120396 0.3048)
			(stroke
				(width 0.1)
				(type default)
			)
			(layer "F.Fab")
		)
		(fp_line
			(start 0.67945 -0.3048)
			(end 0.67945 0.3048)
			(stroke
				(width 0.1)
				(type default)
			)
			(layer "F.Fab")
		)
		(fp_line
			(start 0.12065 -0.2794)
			(end 0.12065 -0.3048)
			(stroke
				(width 0.1)
				(type default)
			)
			(layer "F.Fab")
		)
		(fp_line
			(start 0.12065 -0.3048)
			(end 0.67945 -0.3048)
			(stroke
				(width 0.1)
				(type default)
			)
			(layer "F.Fab")
		)
		(fp_line
			(start 0.120396 0.3048)
			(end 0.120396 0.2794)
			(stroke
				(width 0.1)
				(type default)
			)
			(layer "F.Fab")
		)
		(fp_line
			(start 0.120396 0.2794)
			(end -0.12065 0.2794)
			(stroke
				(width 0.1)
				(type default)
			)
			(layer "F.Fab")
		)
		(fp_line
			(start -0.12065 0.3048)
			(end -0.67945 0.3048)
			(stroke
				(width 0.1)
				(type default)
			)
			(layer "F.Fab")
		)
		(fp_line
			(start -0.12065 0.2794)
			(end -0.12065 0.3048)
			(stroke
				(width 0.1)
				(type default)
			)
			(layer "F.Fab")
		)
		(fp_line
			(start -0.12065 -0.2794)
			(end 0.12065 -0.2794)
			(stroke
				(width 0.1)
				(type default)
			)
			(layer "F.Fab")
		)
		(fp_line
			(start -0.12065 -0.305054)
			(end -0.12065 -0.2794)
			(stroke
				(width 0.1)
				(type default)
			)
			(layer "F.Fab")
		)
		(fp_line
			(start -0.67945 0.3048)
			(end -0.67945 -0.305054)
			(stroke
				(width 0.1)
				(type default)
			)
			(layer "F.Fab")
		)
		(fp_line
			(start -0.67945 -0.305054)
			(end -0.12065 -0.305054)
			(stroke
				(width 0.1)
				(type default)
			)
			(layer "F.Fab")
		)
		(pad "1" smd circle
			(at -0.40005 0 180)
			(size 0 0)
			(layers "F.Cu" "F.Mask" "F.Paste")
			(net "FAN_7_MODE")
		)
		(pad "2" smd circle
			(at 0.40005 0 180)
			(size 0 0)
			(layers "F.Cu" "F.Mask" "F.Paste")
			(net "GND")
		)
	)
	(footprint ""
		(layer "F.Cu")
		(at 45.085 -182.88 180)
		(property "Reference" "R521"
			(at 0 0 180)
			(layer "F.SilkS")
			(hide yes)
			(effects
				(font
					(size 1.27 1.27)
				)
			)
		)
		(property "Value" ""
			(at 0 0 180)
			(layer "F.Fab")
			(effects
				(font
					(size 1.27 1.27)
				)
			)
		)
		(duplicate_pad_numbers_are_jumpers no)
		(fp_line
			(start 0.7874 0.4064)
			(end -0.7874 0.4064)
			(stroke
				(width 0.1524)
				(type default)
			)
			(layer "F.SilkS")
		)
		(fp_line
			(start 0.7874 -0.4064)
			(end 0.7874 0.4064)
			(stroke
				(width 0.1524)
				(type default)
			)
			(layer "F.SilkS")
		)
		(fp_line
			(start -0.7874 0.4064)
			(end -0.7874 -0.4064)
			(stroke
				(width 0.1524)
				(type default)
			)
			(layer "F.SilkS")
		)
		(fp_line
			(start -0.7874 -0.4064)
			(end 0.7874 -0.4064)
			(stroke
				(width 0.1524)
				(type default)
			)
			(layer "F.SilkS")
		)
		(fp_line
			(start 0.67945 0.3048)
			(end 0.120396 0.3048)
			(stroke
				(width 0.1)
				(type default)
			)
			(layer "F.Fab")
		)
		(fp_line
			(start 0.67945 -0.3048)
			(end 0.67945 0.3048)
			(stroke
				(width 0.1)
				(type default)
			)
			(layer "F.Fab")
		)
		(fp_line
			(start 0.12065 -0.2794)
			(end 0.12065 -0.3048)
			(stroke
				(width 0.1)
				(type default)
			)
			(layer "F.Fab")
		)
		(fp_line
			(start 0.12065 -0.3048)
			(end 0.67945 -0.3048)
			(stroke
				(width 0.1)
				(type default)
			)
			(layer "F.Fab")
		)
		(fp_line
			(start 0.120396 0.3048)
			(end 0.120396 0.2794)
			(stroke
				(width 0.1)
				(type default)
			)
			(layer "F.Fab")
		)
		(fp_line
			(start 0.120396 0.2794)
			(end -0.12065 0.2794)
			(stroke
				(width 0.1)
				(type default)
			)
			(layer "F.Fab")
		)
		(fp_line
			(start -0.12065 0.3048)
			(end -0.67945 0.3048)
			(stroke
				(width 0.1)
				(type default)
			)
			(layer "F.Fab")
		)
		(fp_line
			(start -0.12065 0.2794)
			(end -0.12065 0.3048)
			(stroke
				(width 0.1)
				(type default)
			)
			(layer "F.Fab")
		)
		(fp_line
			(start -0.12065 -0.2794)
			(end 0.12065 -0.2794)
			(stroke
				(width 0.1)
				(type default)
			)
			(layer "F.Fab")
		)
		(fp_line
			(start -0.12065 -0.305054)
			(end -0.12065 -0.2794)
			(stroke
				(width 0.1)
				(type default)
			)
			(layer "F.Fab")
		)
		(fp_line
			(start -0.67945 0.3048)
			(end -0.67945 -0.305054)
			(stroke
				(width 0.1)
				(type default)
			)
			(layer "F.Fab")
		)
		(fp_line
			(start -0.67945 -0.305054)
			(end -0.12065 -0.305054)
			(stroke
				(width 0.1)
				(type default)
			)
			(layer "F.Fab")
		)
		(pad "1" smd circle
			(at -0.40005 0 180)
			(size 0 0)
			(layers "F.Cu" "F.Mask" "F.Paste")
			(net "GND")
		)
		(pad "2" smd circle
			(at 0.40005 0 180)
			(size 0 0)
			(layers "F.Cu" "F.Mask" "F.Paste")
			(net "PD_FAN_BUFF_INPUT_U336F")
		)
	)
	(footprint ""
		(layer "F.Cu")
		(at 17.399 -114.681 180)
		(property "Reference" "U362"
			(at -1.651 -1.55067 0)
			(unlocked yes)
			(layer "F.SilkS")
			(effects
				(font
					(size 0.7874 0.5842)
					(thickness 0.1524)
				)
				(justify left)
			)
		)
		(property "Value" ""
			(at 0 0 180)
			(layer "F.Fab")
			(effects
				(font
					(size 1.27 1.27)
				)
			)
		)
		(duplicate_pad_numbers_are_jumpers no)
		(fp_line
			(start 1.335278 1.100074)
			(end 1.335278 -1.100074)
			(stroke
				(width 0.1524)
				(type default)
			)
			(layer "F.SilkS")
		)
		(fp_line
			(start 1.335278 -1.100074)
			(end -1.335278 -1.100074)
			(stroke
				(width 0.1524)
				(type default)
			)
			(layer "F.SilkS")
		)
		(fp_line
			(start -1.335278 1.100074)
			(end 1.335278 1.100074)
			(stroke
				(width 0.1524)
				(type default)
			)
			(layer "F.SilkS")
		)
		(fp_line
			(start -1.335278 -1.100074)
			(end -1.335278 1.100074)
			(stroke
				(width 0.1524)
				(type default)
			)
			(layer "F.SilkS")
		)
		(fp_line
			(start 0.674878 1.100074)
			(end 0.674878 -1.100074)
			(stroke
				(width 0.1)
				(type default)
			)
			(layer "F.Fab")
		)
		(fp_line
			(start 0.674878 -1.100074)
			(end -0.674878 -1.100074)
			(stroke
				(width 0.1)
				(type default)
			)
			(layer "F.Fab")
		)
		(fp_line
			(start -0.674878 1.100074)
			(end 0.674878 1.100074)
			(stroke
				(width 0.1)
				(type default)
			)
			(layer "F.Fab")
		)
		(fp_line
			(start -0.674878 -1.100074)
			(end -0.674878 1.100074)
			(stroke
				(width 0.1)
				(type default)
			)
			(layer "F.Fab")
		)
		(pad "D" smd rect
			(at 0.8001 0 90)
			(size 0.6096 0.8128)
			(layers "F.Cu" "F.Mask" "F.Paste")
			(net "FAN_5_OK_LED_R_N")
		)
		(pad "G" smd rect
			(at -0.8001 -0.649986 90)
			(size 0.6096 0.8128)
			(layers "F.Cu" "F.Mask" "F.Paste")
			(net "FAN_5_OK_R_LED")
		)
		(pad "S" smd rect
			(at -0.8001 0.649986 90)
			(size 0.6096 0.8128)
			(layers "F.Cu" "F.Mask" "F.Paste")
			(net "GND")
		)
	)
	(footprint ""
		(layer "F.Cu")
		(at 43.561 -171.831)
		(property "Reference" "R5096"
			(at 0 0 0)
			(layer "F.SilkS")
			(hide yes)
			(effects
				(font
					(size 1.27 1.27)
				)
			)
		)
		(property "Value" ""
			(at 0 0 0)
			(layer "F.Fab")
			(effects
				(font
					(size 1.27 1.27)
				)
			)
		)
		(duplicate_pad_numbers_are_jumpers no)
		(fp_line
			(start -0.7874 -0.4064)
			(end 0.7874 -0.4064)
			(stroke
				(width 0.1524)
				(type default)
			)
			(layer "F.SilkS")
		)
		(fp_line
			(start -0.7874 0.4064)
			(end -0.7874 -0.4064)
			(stroke
				(width 0.1524)
				(type default)
			)
			(layer "F.SilkS")
		)
		(fp_line
			(start 0.7874 -0.4064)
			(end 0.7874 0.4064)
			(stroke
				(width 0.1524)
				(type default)
			)
			(layer "F.SilkS")
		)
		(fp_line
			(start 0.7874 0.4064)
			(end -0.7874 0.4064)
			(stroke
				(width 0.1524)
				(type default)
			)
			(layer "F.SilkS")
		)
		(fp_line
			(start -0.67945 -0.305054)
			(end -0.12065 -0.305054)
			(stroke
				(width 0.1)
				(type default)
			)
			(layer "F.Fab")
		)
		(fp_line
			(start -0.67945 0.3048)
			(end -0.67945 -0.305054)
			(stroke
				(width 0.1)
				(type default)
			)
			(layer "F.Fab")
		)
		(fp_line
			(start -0.12065 -0.305054)
			(end -0.12065 -0.2794)
			(stroke
				(width 0.1)
				(type default)
			)
			(layer "F.Fab")
		)
		(fp_line
			(start -0.12065 -0.2794)
			(end 0.12065 -0.2794)
			(stroke
				(width 0.1)
				(type default)
			)
			(layer "F.Fab")
		)
		(fp_line
			(start -0.12065 0.2794)
			(end -0.12065 0.3048)
			(stroke
				(width 0.1)
				(type default)
			)
			(layer "F.Fab")
		)
		(fp_line
			(start -0.12065 0.3048)
			(end -0.67945 0.3048)
			(stroke
				(width 0.1)
				(type default)
			)
			(layer "F.Fab")
		)
		(fp_line
			(start 0.120396 0.2794)
			(end -0.12065 0.2794)
			(stroke
				(width 0.1)
				(type default)
			)
			(layer "F.Fab")
		)
		(fp_line
			(start 0.120396 0.3048)
			(end 0.120396 0.2794)
			(stroke
				(width 0.1)
				(type default)
			)
			(layer "F.Fab")
		)
		(fp_line
			(start 0.12065 -0.3048)
			(end 0.67945 -0.3048)
			(stroke
				(width 0.1)
				(type default)
			)
			(layer "F.Fab")
		)
		(fp_line
			(start 0.12065 -0.2794)
			(end 0.12065 -0.3048)
			(stroke
				(width 0.1)
				(type default)
			)
			(layer "F.Fab")
		)
		(fp_line
			(start 0.67945 -0.3048)
			(end 0.67945 0.3048)
			(stroke
				(width 0.1)
				(type default)
			)
			(layer "F.Fab")
		)
		(fp_line
			(start 0.67945 0.3048)
			(end 0.120396 0.3048)
			(stroke
				(width 0.1)
				(type default)
			)
			(layer "F.Fab")
		)
		(pad "1" smd circle
			(at -0.40005 0)
			(size 0 0)
			(layers "F.Cu" "F.Mask" "F.Paste")
			(net "FAN_1_OK_LED")
		)
		(pad "2" smd circle
			(at 0.40005 0)
			(size 0 0)
			(layers "F.Cu" "F.Mask" "F.Paste")
			(net "FAN_1_OK_R_LED")
		)
	)
)
